FILE_TYPE = CONNECTIVITY;
{Allegro Design Entry HDL 17.2-2016 S081 (4005846) 1/11/2022}
"PAGE_NUMBER" = 254;
0"NC";
1"PVCCIN_CPU0_PVCC\g";
2"PVCCIN_CPU0_PVCC\g";
3"SW_P12V_PVCCIN_CPU0_FLT\g";
4"SW_P12V_PVCCIN_CPU0_FLT\g";
5"PVCCIN_CPU0\g";
6"PVCCIN_CPU0\g";
7"GND\g";
8"GND\g";
9"GND\g";
10"GND\g";
11"GND\g";
12"GND\g";
13"GND\g";
14"GND\g";
15"GND\g";
16"GND\g";
17"GND\g";
18"GND\g";
19"GND\g";
20"GND\g";
21"PVCCIN_CPU0_LSET3";
22"IND_P0_CPL4";
23"IND_P0_CPL3";
24"SW_PVCCIN_CPU0_BOOT3_R";
25"SW_PVCCIN_CPU0_BOOTR3";
26"SW_PVCCIN_CPU0_SW3";
27"SW_PVCCIN_CPU0_BOOT3";
28"PVCCIN_CPU0_VOS3";
29"IND_P0_CPL5";
30"SW_PVCCIN_CPU0_BOOT4";
31"SW_PVCCIN_CPU0_BOOT4_R";
32"IND_P0_CPL4";
33"SW_PVCCIN_CPU0_BOOTR4";
34"SW_PVCCIN_CPU0_SW4";
35"PVCCIN_CPU0_VOS4";
36"PVCCIN_CPU0_VDD3";
37"PVCCIN_CPU0_VREF"CDS_PHYS_NET_NAME"PVCCIN_CPU0_VREF";
38"PVCCIN_CPU0_IMON3";
39"PVCCIN_CPU0_ATSEN";
40"PVCCIN_CPU0_PWM3";
41"PVCCIN_CPU0_VDD4";
42"PVCCIN_CPU0_IMON4";
43"PVCCIN_CPU0_PWM4";
44"PVCCIN_CPU0_ATSEN";
45"PVCCIN_CPU0_VREF"CDS_PHYS_NET_NAME"PVCCIN_CPU0_VREF";
46"PVCCIN_CPU0_LSET4";
%"UNIVERSAL_GND"
"1","(2600,775)","0","logical_power","I1";
;
CDS_LIB"logical_power"
HDL_POWER"GND";
"A"7;
%"UNIVERSAL_GND"
"1","(3000,1750)","0","logical_power","I10";
;
CDS_LIB"logical_power"
HDL_POWER"GND";
"A"10;
%"Q_CAP"
"1","(3000,2000)","0","pure_quanta","I11";
;
PART_NUMBER"CH5222KEB01"
MATERIAL"X6S"
TOLERANCE"10%"
VALUE"2.2UF"
VOLTAGE"10V"
PACK_TYPE"C0402"
LOCATION"PC270"
CDS_LIB"pure_quanta"
LOCATION"PC270"
$SEC"1"
CDS_SEC"1";
"B"
$PN"2"10;
"A"
$PN"1"41;
%"Q_CAP"
"2","(3325,1300)","0","pure_quanta","I12";
;
PART_NUMBER"CH4104K1B00"
PACK_TYPE"0402"
TOLERANCE"10%"
MATERIAL"X7R"
VALUE"0.1UF"
VOLTAGE"25V"
LOCATION"PC1340"
CDS_LIB"pure_quanta"
$SEC"1"
CDS_SEC"1";
"A"
$PN"1"8;
"B"
$PN"2"45;
%"ISL99390FRZTR5935"
"1","(4525,1500)","0","pure_quanta","I13";
;
PART_NUMBER"AL099390004"
PART_TYPE"SMLF"
MATERIAL"IC"
VALUE"ISL99390FRZ-TR5935"
LOCATION"PU10_P0_4"
CDS_LIB"pure_quanta"
CDS_LMAN_SYM_OUTLINE"-300,700,250,-650"
NEEDS_NO_SIZE"TRUE"
$SEC"1"
CDS_SEC"1";
"PGND2"
$PN"7_9-20_24"15;
"GL2"
$PN"41"0;
"GL1"
$PN"6"0;
"DNC"
$PN"31"0;
"EN"
$PN"35"41;
"PGND3"
$PN"40"15;
"VOS"
$PN"1"35;
"VIN2"
$PN"30"3;
"PGND1"
$PN"5"15;
"SW"
$PN"10_19"34;
"LSET"
$PN"37"46;
"IOUT"
$PN"38"42;
"TOUT_FLT"
$PN"36"44;
"PVCC"
$PN"4"1;
"PHASE"
$PN"32"33;
"VIN1"
$PN"25_29"3;
"BOOT"
$PN"33"30;
"AGND"
$PN"2"15;
"VCC"
$PN"3"41;
"REFIN"
$PN"39"45;
"PWM"
$PN"34"43;
%"Q_RES"
"2","(3000,2500)","0","pure_quanta","I14";
;
PART_NUMBER"CS-2202FB01"
WATTAGE"1/16W"
MATERIAL"CHIP"
TOLERANCE"1%"
VALUE"2.2"
PACK_TYPE"0402LF"
LOCATION"PR146"
CDS_LIB"pure_quanta"
$SEC"1"
CDS_SEC"1";
"A"
$PN"1"1;
"B"
$PN"2"41;
%"VCC15"
"1","(3000,2825)","0","logical_power","I15";
;
HDL_POWER"PVCCIN_CPU0_PVCC"
CDS_LIB"logical_power";
"A"1;
%"UNIVERSAL_GND"
"1","(3425,2275)","0","logical_power","I16";
;
CDS_LIB"logical_power"
HDL_POWER"GND";
"A"11;
%"Q_CAP"
"1","(3425,2500)","0","pure_quanta","I17";
;
PART_NUMBER"CH5222KEB01"
MATERIAL"X6S"
VALUE"2.2UF"
VOLTAGE"10V"
PACK_TYPE"C0402"
TOLERANCE"10%"
LOCATION"PC272_P0_4"
CDS_LIB"pure_quanta"
LOCATION"PC272_P0_4"
$SEC"1"
CDS_SEC"1";
"B"
$PN"2"11;
"A"
$PN"1"1;
%"Q_RES"
"2","(2600,1000)","2","pure_quanta","I2";
;
PART_NUMBER"CS28872FB01"
PACK_TYPE"0402LF"
WATTAGE"1/16W"
MATERIAL"EMPTY"
TOLERANCE"1%"
VALUE"8.87K"
LOCATION"PR144"
CDS_LIB"pure_quanta"
$SEC"1"
CDS_SEC"1";
"A"
$PN"1"46;
"B"
$PN"2"7;
%"ISL99390FRZTR5935"
"1","(4550,4325)","0","pure_quanta","I20";
;
PART_NUMBER"AL099390004"
PART_TYPE"SMLF"
MATERIAL"IC"
VALUE"ISL99390FRZ-TR5935"
LOCATION"PU11_P0_3"
CDS_LIB"pure_quanta"
CDS_LMAN_SYM_OUTLINE"-300,700,250,-650"
NEEDS_NO_SIZE"TRUE"
$SEC"1"
CDS_SEC"1";
"PGND2"
$PN"7_9-20_24"16;
"GL2"
$PN"41"0;
"GL1"
$PN"6"0;
"DNC"
$PN"31"0;
"EN"
$PN"35"36;
"PGND3"
$PN"40"16;
"VOS"
$PN"1"28;
"VIN2"
$PN"30"4;
"PGND1"
$PN"5"16;
"SW"
$PN"10_19"26;
"LSET"
$PN"37"21;
"IOUT"
$PN"38"38;
"TOUT_FLT"
$PN"36"39;
"PVCC"
$PN"4"2;
"PHASE"
$PN"32"25;
"VIN1"
$PN"25_29"4;
"BOOT"
$PN"33"27;
"AGND"
$PN"2"16;
"VCC"
$PN"3"36;
"REFIN"
$PN"39"37;
"PWM"
$PN"34"40;
%"UNIVERSAL_GND"
"1","(2525,4050)","0","logical_power","I21";
;
CDS_LIB"logical_power"
HDL_POWER"GND";
"A"12;
%"UNIVERSAL_GND"
"1","(3025,4575)","0","logical_power","I24";
;
CDS_LIB"logical_power"
HDL_POWER"GND";
"A"13;
%"Q_CAP"
"1","(3025,4825)","0","pure_quanta","I25";
;
PART_NUMBER"CH5222KEB01"
MATERIAL"X6S"
TOLERANCE"10%"
VALUE"2.2UF"
VOLTAGE"10V"
PACK_TYPE"C0402"
LOCATION"PC271"
CDS_LIB"pure_quanta"
LOCATION"PC271"
$SEC"1"
CDS_SEC"1";
"B"
$PN"2"13;
"A"
$PN"1"36;
%"Q_CAP"
"2","(3350,4125)","0","pure_quanta","I26";
;
PART_NUMBER"CH4104K1B00"
VOLTAGE"25V"
MATERIAL"X7R"
TOLERANCE"10%"
PACK_TYPE"0402"
VALUE"0.1UF"
LOCATION"PC1341"
CDS_LIB"pure_quanta"
$SEC"1"
CDS_SEC"1";
"A"
$PN"1"12;
"B"
$PN"2"37;
%"Q_RES"
"2","(3025,5325)","0","pure_quanta","I27";
;
PART_NUMBER"CS-2202FB01"
WATTAGE"1/16W"
MATERIAL"CHIP"
TOLERANCE"1%"
VALUE"2.2"
PACK_TYPE"0402LF"
LOCATION"PR147"
CDS_LIB"pure_quanta"
LOCATION"PR147"
$SEC"1"
CDS_SEC"1";
"A"
$PN"1"2;
"B"
$PN"2"36;
%"VCC15"
"1","(3025,5650)","0","logical_power","I28";
;
HDL_POWER"PVCCIN_CPU0_PVCC"
CDS_LIB"logical_power";
"A"2;
%"UNIVERSAL_GND"
"1","(3450,5100)","0","logical_power","I29";
;
CDS_LIB"logical_power"
HDL_POWER"GND";
"A"14;
%"UNIVERSAL_GND"
"1","(2500,1225)","0","logical_power","I3";
;
CDS_LIB"logical_power"
HDL_POWER"GND";
"A"8;
%"Q_CAP"
"1","(3450,5325)","0","pure_quanta","I30";
;
PART_NUMBER"CH5222KEB01"
MATERIAL"X6S"
TOLERANCE"10%"
VALUE"2.2UF"
VOLTAGE"10V"
PACK_TYPE"C0402"
LOCATION"PC273_P0_3"
CDS_LIB"pure_quanta"
LOCATION"PC273_P0_3"
$SEC"1"
CDS_SEC"1";
"B"
$PN"2"14;
"A"
$PN"1"2;
%"UNIVERSAL_GND"
"1","(5175,775)","0","logical_power","I31";
;
CDS_LIB"logical_power"
HDL_POWER"GND";
"A"15;
%"Q_INDUCTOR4P_14"
"1","(6950,1375)","0","pure_quanta","I33";
;
PART_NUMBER"CV+15^0TZ04"
PART_TYPE"SMLF"
VALUE"150NH"
MATERIAL"IND"
LOCATION"PL11"
SEC_TYPE""
CDS_LIB"pure_quanta"
NEEDS_NO_SIZE"TRUE"
SEC"1";
"1"
$PN"1"34;
"4"
$PN"4"5;
"3"
$PN"3"29;
"2"
$PN"2"32;
%"Q_CAP"
"1","(6500,1775)","2","pure_quanta","I34";
;
PART_NUMBER"CH4106K1B01"
MATERIAL"X7R"
TOLERANCE"10%"
VALUE"100NF"
VOLTAGE"50V"
PACK_TYPE"C0402"
LOCATION"PC278"
CDS_LIB"pure_quanta"
$SEC"1"
CDS_SEC"1";
"B"
$PN"2"33;
"A"
$PN"1"31;
%"Q_CAP"
"1","(5325,2400)","0","pure_quanta","I35";
;
PART_NUMBER"TMP_QCH2336K1B12"
VALUE"3300PF"
MATERIAL"X7R"
TOLERANCE"10%"
VOLTAGE"50V"
PACK_TYPE"0402"
LOCATION"PC274_P0_4"
CDS_LIB"pure_quanta"
LOCATION"PC274_P0_4"
$SEC"1"
CDS_SEC"1";
"B"
$PN"2"17;
"A"
$PN"1"3;
%"Q_RES"
"1","(5775,1950)","0","pure_quanta","I36";
;
PART_NUMBER"CS-3302FB01"
VALUE"3.3"
TOLERANCE"1%"
WATTAGE"1/16W"
MATERIAL"CHIP"
PACK_TYPE"0402LF"
LOCATION"PR1768"
CDS_LIB"pure_quanta"
$SEC"1"
CDS_SEC"1";
"B"
$PN"2"31;
"A"
$PN"1"30;
%"UNIVERSAL_GND"
"1","(5200,3600)","0","logical_power","I37";
;
CDS_LIB"logical_power"
HDL_POWER"GND";
"A"16;
%"Q_CAP"
"1","(5725,2400)","0","pure_quanta","I38";
;
PART_NUMBER"CH5103KEB01"
TOLERANCE"10%"
MATERIAL"X6S"
VALUE"1UF"
VOLTAGE"16V"
PACK_TYPE"C0402"
LOCATION"PC276_P0_4"
CDS_LIB"pure_quanta"
LOCATION"PC276_P0_4"
$SEC"1"
CDS_SEC"1";
"B"
$PN"2"17;
"A"
$PN"1"3;
%"Q_CAP"
"1","(6125,2400)","0","pure_quanta","I39";
;
PART_NUMBER"CH6223MEA01"
PACK_TYPE"C0805"
MATERIAL"X6S"
TOLERANCE"20%"
VALUE"22UF"
VOLTAGE"16V"
LOCATION"PC280_P0_4"
CDS_LIB"pure_quanta"
LOCATION"PC280_P0_4"
$SEC"1"
CDS_SEC"1";
"B"
$PN"2"17;
"A"
$PN"1"3;
%"Q_RES"
"2","(2625,3825)","2","pure_quanta","I4";
;
PART_NUMBER"CS28872FB01"
MATERIAL"EMPTY"
TOLERANCE"1%"
VALUE"8.87K"
PACK_TYPE"0402LF"
WATTAGE"1/16W"
LOCATION"PR145"
CDS_LIB"pure_quanta"
$SEC"1"
CDS_SEC"1";
"A"
$PN"1"21;
"B"
$PN"2"9;
%"Q_CAP"
"1","(6525,2400)","0","pure_quanta","I40";
;
PART_NUMBER"CH6223MEA01"
MATERIAL"X6S"
TOLERANCE"20%"
VOLTAGE"16V"
PACK_TYPE"C0805"
VALUE"22UF"
LOCATION"PC282_P0_4"
CDS_LIB"pure_quanta"
LOCATION"PC282_P0_4"
$SEC"1"
CDS_SEC"1";
"B"
$PN"2"17;
"A"
$PN"1"3;
%"Q_RES"
"1","(7075,975)","0","pure_quanta","I41";
;
PART_NUMBER"CS00002JB13"
MATERIAL"CHIP"
TOLERANCE"5%"
VALUE"0"
PACK_TYPE"0402LF"
WATTAGE"1/16W"
LOCATION"PR148"
CDS_LIB"pure_quanta"
$SEC"1"
CDS_SEC"1";
"B"
$PN"2"5;
"A"
$PN"1"35;
%"Q_CAP"
"1","(6900,2400)","0","pure_quanta","I43";
;
PART_NUMBER"CH6223MEA01"
PACK_TYPE"C0805"
VALUE"22UF"
TOLERANCE"20%"
MATERIAL"X6S"
VOLTAGE"16V"
LOCATION"PC284_P0_4"
CDS_LIB"pure_quanta"
LOCATION"PC284_P0_4"
$SEC"1"
CDS_SEC"1";
"B"
$PN"2"17;
"A"
$PN"1"3;
%"UNIVERSAL_GND"
"1","(7125,1975)","0","logical_power","I44";
;
CDS_LIB"logical_power"
HDL_POWER"GND";
"A"17;
%"VCC15"
"1","(7125,2775)","0","logical_power","I45";
;
HDL_POWER"SW_P12V_PVCCIN_CPU0_FLT"
CDS_LIB"logical_power";
"A"3;
%"Q_RES"
"1","(7100,3775)","0","pure_quanta","I46";
;
PART_NUMBER"CS00002JB13"
MATERIAL"CHIP"
VALUE"0"
PACK_TYPE"0402LF"
TOLERANCE"5%"
WATTAGE"1/16W"
LOCATION"PR149"
CDS_LIB"pure_quanta"
$SEC"1"
CDS_SEC"1";
"B"
$PN"2"6;
"A"
$PN"1"28;
%"Q_CAP"
"1","(5350,5225)","0","pure_quanta","I48";
;
PART_NUMBER"TMP_QCH2336K1B12"
MATERIAL"X7R"
TOLERANCE"10%"
VALUE"3300PF"
VOLTAGE"50V"
PACK_TYPE"0402"
LOCATION"PC275_P0_3"
CDS_LIB"pure_quanta"
LOCATION"PC275_P0_3"
$SEC"1"
CDS_SEC"1";
"B"
$PN"2"18;
"A"
$PN"1"4;
%"Q_RES"
"1","(5800,4775)","0","pure_quanta","I49";
;
PART_NUMBER"CS-3302FB01"
MATERIAL"CHIP"
PACK_TYPE"0402LF"
WATTAGE"1/16W"
VALUE"3.3"
TOLERANCE"1%"
LOCATION"PR1769"
CDS_LIB"pure_quanta"
$SEC"1"
CDS_SEC"1";
"B"
$PN"2"24;
"A"
$PN"1"27;
%"UNIVERSAL_GND"
"1","(2625,3600)","0","logical_power","I5";
;
CDS_LIB"logical_power"
HDL_POWER"GND";
"A"9;
%"Q_INDUCTOR4P_14"
"1","(7000,4200)","0","pure_quanta","I50";
;
PART_NUMBER"CV+15^0TZ04"
PART_TYPE"SMLF"
MATERIAL"IND"
VALUE"150NH"
LOCATION"PL112"
SEC_TYPE""
CDS_LIB"pure_quanta"
NEEDS_NO_SIZE"TRUE"
SEC"1";
"1"
$PN"1"26;
"4"
$PN"4"6;
"3"
$PN"3"22;
"2"
$PN"2"23;
%"Q_CAP"
"1","(6525,4600)","2","pure_quanta","I51";
;
PART_NUMBER"CH4106K1B01"
TOLERANCE"10%"
VALUE"100NF"
VOLTAGE"50V"
MATERIAL"X7R"
PACK_TYPE"C0402"
LOCATION"PC279"
CDS_LIB"pure_quanta"
$SEC"1"
CDS_SEC"1";
"B"
$PN"2"25;
"A"
$PN"1"24;
%"Q_CAP"
"1","(5750,5225)","0","pure_quanta","I52";
;
PART_NUMBER"CH5103KEB01"
MATERIAL"X6S"
TOLERANCE"10%"
VALUE"1UF"
VOLTAGE"16V"
PACK_TYPE"C0402"
LOCATION"PC277_P0_3"
CDS_LIB"pure_quanta"
LOCATION"PC277_P0_3"
$SEC"1"
CDS_SEC"1";
"B"
$PN"2"18;
"A"
$PN"1"4;
%"Q_CAP"
"1","(6150,5225)","0","pure_quanta","I53";
;
PART_NUMBER"CH6223MEA01"
MATERIAL"X6S"
TOLERANCE"20%"
VALUE"22UF"
VOLTAGE"16V"
PACK_TYPE"C0805"
LOCATION"PC281_P0_3"
CDS_LIB"pure_quanta"
LOCATION"PC281_P0_3"
$SEC"1"
CDS_SEC"1";
"B"
$PN"2"18;
"A"
$PN"1"4;
%"Q_CAP"
"1","(6550,5225)","0","pure_quanta","I54";
;
PART_NUMBER"CH6223MEA01"
MATERIAL"X6S"
TOLERANCE"20%"
VALUE"22UF"
VOLTAGE"16V"
PACK_TYPE"C0805"
LOCATION"PC283_P0_3"
CDS_LIB"pure_quanta"
LOCATION"PC283_P0_3"
$SEC"1"
CDS_SEC"1";
"B"
$PN"2"18;
"A"
$PN"1"4;
%"UNIVERSAL_GND"
"1","(7150,4800)","0","logical_power","I55";
;
CDS_LIB"logical_power"
HDL_POWER"GND";
"A"18;
%"Q_CAP"
"1","(6925,5225)","0","pure_quanta","I56";
;
PART_NUMBER"CH6223MEA01"
MATERIAL"X6S"
TOLERANCE"20%"
VALUE"22UF"
VOLTAGE"16V"
PACK_TYPE"C0805"
LOCATION"PC285_P0_3"
CDS_LIB"pure_quanta"
LOCATION"PC285_P0_3"
$SEC"1"
CDS_SEC"1";
"B"
$PN"2"18;
"A"
$PN"1"4;
%"VCC15"
"1","(7150,5600)","0","logical_power","I57";
;
HDL_POWER"SW_P12V_PVCCIN_CPU0_FLT"
CDS_LIB"logical_power";
"A"4;
%"Q_CAP"
"1","(8750,4125)","0","pure_quanta","I59";
;
PART_NUMBER"CH622KMEA03"
PACK_TYPE"C0805"
VOLTAGE"4V"
VALUE"22UF"
TOLERANCE"20%"
MATERIAL"X6S"
LOCATION"PC289_P0_3"
CDS_LIB"pure_quanta"
LOCATION"PC289_P0_3"
$SEC"1"
CDS_SEC"1";
"B"
$PN"2"20;
"A"
$PN"1"6;
%"Q_CAP"
"1","(8775,1300)","0","pure_quanta","I60";
;
PART_NUMBER"CH622KMEA03"
PACK_TYPE"C0805"
VOLTAGE"4V"
VALUE"22UF"
TOLERANCE"20%"
MATERIAL"X6S"
LOCATION"PC288_P0_4"
CDS_LIB"pure_quanta"
LOCATION"PC288_P0_4"
$SEC"1"
CDS_SEC"1";
"B"
$PN"2"19;
"A"
$PN"1"5;
%"Q_CAP"
"1","(9200,1300)","0","pure_quanta","I61";
;
PART_NUMBER"CH622KMEA03"
PACK_TYPE"C0805"
VOLTAGE"4V"
VALUE"22UF"
TOLERANCE"20%"
MATERIAL"X6S"
LOCATION"PC290_P0_4"
CDS_LIB"pure_quanta"
LOCATION"PC290_P0_4"
$SEC"1"
CDS_SEC"1";
"B"
$PN"2"19;
"A"
$PN"1"5;
%"UNIVERSAL_GND"
"1","(9500,925)","0","logical_power","I62";
;
CDS_LIB"logical_power"
HDL_POWER"GND";
"A"19;
%"VCC15"
"1","(9500,1700)","0","logical_power","I63";
;
HDL_POWER"PVCCIN_CPU0"
CDS_LIB"logical_power";
"A"5;
%"UNIVERSAL_GND"
"1","(9475,3750)","0","logical_power","I64";
;
CDS_LIB"logical_power"
HDL_POWER"GND";
"A"20;
%"Q_CAP"
"1","(9175,4125)","0","pure_quanta","I65";
;
PART_NUMBER"CH622KMEA03"
PACK_TYPE"C0805"
VOLTAGE"4V"
VALUE"22UF"
TOLERANCE"20%"
MATERIAL"X6S"
LOCATION"PC291_P0_3"
CDS_LIB"pure_quanta"
LOCATION"PC291_P0_3"
$SEC"1"
CDS_SEC"1";
"B"
$PN"2"20;
"A"
$PN"1"6;
%"VCC15"
"1","(9475,4525)","0","logical_power","I66";
;
HDL_POWER"PVCCIN_CPU0"
CDS_LIB"logical_power";
"A"6;
END.
